(kicad_pcb
	(version 20260206)
	(generator "pcbnew")
	(generator_version "10.0")
	(general
		(thickness 1.6)
		(legacy_teardrops no)
	)
	(paper "A4")
	(title_block
		(title "Bryce Canyon_IOM_IOC_16318-2_OCP.brd")
		(comment 1 "Bryce Canyon / footprints 7-12 of 1605")
	)
	(layers
		(0 "F.Cu" signal "TOP")
		(4 "In1.Cu" signal "L2GND")
		(6 "In2.Cu" signal "L3")
		(8 "In3.Cu" signal "L4VCC")
		(10 "In4.Cu" signal "L5VCC")
		(12 "In5.Cu" signal "L6")
		(14 "In6.Cu" signal "L7GND")
		(2 "B.Cu" signal "BOTTOM")
		(9 "F.Adhes" user "F.Adhesive")
		(11 "B.Adhes" user "B.Adhesive")
		(13 "F.Paste" user "Package Geometry/Pastemask Top")
		(15 "B.Paste" user "Package Geometry/Pastemask Bottom")
		(5 "F.SilkS" user "Ref Des/Silkscreen Top")
		(7 "B.SilkS" user "Ref Des/Silkscreen Bottom")
		(1 "F.Mask" user "Board Geometry/Soldermask Top")
		(3 "B.Mask" user "Board Geometry/Soldermask Bottom")
		(17 "Dwgs.User" user "User.Drawings")
		(19 "Cmts.User" user "User.Comments")
		(21 "Eco1.User" user "User.Eco1")
		(23 "Eco2.User" user "User.Eco2")
		(25 "Edge.Cuts" user "Board Geometry/Outline")
		(27 "Margin" user)
		(31 "F.CrtYd" user "Package Geometry/Place Bound Top")
		(29 "B.CrtYd" user "Package Geometry/Place Bound Bottom")
		(35 "F.Fab" user "Ref Des/Assembly Top")
		(33 "B.Fab" user "Ref Des/Assembly Bottom")
	)
	(footprint ""
		(layer "F.Cu")
		(at 16.691356 -169.1259 -90)
		(property "Reference" "PU10"
			(at 0 0 270)
			(layer "F.SilkS")
			(hide yes)
			(effects
				(font
					(size 1.27 1.27)
				)
			)
		)
		(property "Value" "TPS74801RGW-GP"
			(at -4.7244 -6.223 270)
			(unlocked yes)
			(layer "F.Fab")
			(hide yes)
			(effects
				(font
					(size 1.016 1.016)
					(thickness 0.1524)
				)
			)
		)
		(property "Device Type" "QFN20-1G3D15H40"
			(at -4.7244 -7.747 270)
			(unlocked yes)
			(layer "F.Fab")
			(hide yes)
			(effects
				(font
					(size 1.016 1.016)
					(thickness 0.1524)
				)
			)
		)
		(duplicate_pad_numbers_are_jumpers no)
		(fp_line
			(start -3.5179 3.5179)
			(end -2.2479 3.5179)
			(stroke
				(width 0.1524)
				(type default)
			)
			(layer "F.SilkS")
		)
		(fp_line
			(start 2.2479 3.5179)
			(end 3.5179 3.5179)
			(stroke
				(width 0.1524)
				(type default)
			)
			(layer "F.SilkS")
		)
		(fp_line
			(start 3.5179 3.5179)
			(end 3.5179 2.2479)
			(stroke
				(width 0.1524)
				(type default)
			)
			(layer "F.SilkS")
		)
		(fp_line
			(start 1.299972 3.160522)
			(end 1.299972 3.668522)
			(stroke
				(width 0.1524)
				(type default)
			)
			(layer "F.SilkS")
		)
		(fp_line
			(start -3.5179 2.2479)
			(end -3.5179 3.5179)
			(stroke
				(width 0.1524)
				(type default)
			)
			(layer "F.SilkS")
		)
		(fp_line
			(start -3.160522 1.299972)
			(end -3.922522 1.299972)
			(stroke
				(width 0.1524)
				(type default)
			)
			(layer "F.SilkS")
		)
		(fp_line
			(start 3.160522 -1.299972)
			(end 3.922522 -1.299972)
			(stroke
				(width 0.1524)
				(type default)
			)
			(layer "F.SilkS")
		)
		(fp_line
			(start -1.299972 -3.160522)
			(end -1.299972 -3.668522)
			(stroke
				(width 0.1524)
				(type default)
			)
			(layer "F.SilkS")
		)
		(fp_line
			(start -3.5179 -3.5179)
			(end -3.5179 -2.2479)
			(stroke
				(width 0.1524)
				(type default)
			)
			(layer "F.SilkS")
		)
		(fp_line
			(start -2.2479 -3.5179)
			(end -3.5179 -3.5179)
			(stroke
				(width 0.1524)
				(type default)
			)
			(layer "F.SilkS")
		)
		(fp_poly
			(pts
				(xy 3.5179 -3.5179) (xy 2.2479 -3.5179) (xy 3.5179 -2.2479)
			)
			(stroke
				(width 0)
				(type default)
			)
			(fill yes)
			(layer "F.SilkS")
		)
		(fp_rect
			(start -2.5019 2.5019)
			(end 2.5019 -2.5019)
			(stroke
				(width 0)
				(type default)
			)
			(fill no)
			(layer "F.CrtYd")
		)
		(fp_poly
			(pts
				(xy -3.5179 3.5179) (xy -3.5179 -3.5179) (xy 3.5179 -3.5179) (xy 3.5179 -2.5019) (xy -2.5019 -2.5019)
				(xy -2.5019 2.5019) (xy 2.5019 2.5019) (xy 2.5019 -2.49682) (xy 3.5179 -2.49682) (xy 3.5179 3.5179)
			)
			(stroke
				(width 0)
				(type default)
			)
			(fill no)
			(layer "F.CrtYd")
		)
		(fp_rect
			(start -3.5179 3.5179)
			(end 3.5179 -3.5179)
			(stroke
				(width 0)
				(type default)
			)
			(fill no)
			(layer "F.Fab")
		)
		(pad "1" smd rect
			(at 1.299972 -2.474722 270)
			(size 0.3556 1.0668)
			(layers "F.Cu" "F.Mask" "F.Paste")
			(net "TPS74801_P1V2_STBY_OUT")
		)
		(pad "2" smd rect
			(at 0.649986 -2.474722 270)
			(size 0.3556 1.0668)
			(layers "F.Cu" "F.Mask" "F.Paste")
			(net "GND")
		)
		(pad "3" smd rect
			(at 0 -2.474722 270)
			(size 0.3556 1.0668)
			(layers "F.Cu" "F.Mask" "F.Paste")
			(net "GND")
		)
		(pad "4" smd rect
			(at -0.649986 -2.474722 270)
			(size 0.3556 1.0668)
			(layers "F.Cu" "F.Mask" "F.Paste")
			(net "GND")
		)
		(pad "5" smd rect
			(at -1.299972 -2.474722 270)
			(size 0.3556 1.0668)
			(layers "F.Cu" "F.Mask" "F.Paste")
			(net "P1V8_STBY")
		)
		(pad "6" smd rect
			(at -2.474722 -1.299972 270)
			(size 1.0668 0.3556)
			(layers "F.Cu" "F.Mask" "F.Paste")
			(net "P1V8_STBY")
		)
		(pad "7" smd rect
			(at -2.474722 -0.649986 270)
			(size 1.0668 0.3556)
			(layers "F.Cu" "F.Mask" "F.Paste")
			(net "P1V8_STBY")
		)
		(pad "8" smd rect
			(at -2.474722 0 270)
			(size 1.0668 0.3556)
			(layers "F.Cu" "F.Mask" "F.Paste")
			(net "P1V8_STBY")
		)
		(pad "9" smd rect
			(at -2.474722 0.649986 270)
			(size 1.0668 0.3556)
			(layers "F.Cu" "F.Mask" "F.Paste")
			(net "PWRGD_P1V2_STBY")
		)
		(pad "10" smd rect
			(at -2.474722 1.299972 270)
			(size 1.0668 0.3556)
			(layers "F.Cu" "F.Mask" "F.Paste")
			(net "TPS74801_P1V2_STBY_BIAS")
		)
		(pad "11" smd rect
			(at -1.299972 2.474722 270)
			(size 0.3556 1.0668)
			(layers "F.Cu" "F.Mask" "F.Paste")
			(net "TPS74801_P1V2_STBY_EN")
		)
		(pad "12" smd rect
			(at -0.649986 2.474722 270)
			(size 0.3556 1.0668)
			(layers "F.Cu" "F.Mask" "F.Paste")
			(net "GND")
		)
		(pad "13" smd rect
			(at 0 2.474722 270)
			(size 0.3556 1.0668)
			(layers "F.Cu" "F.Mask" "F.Paste")
			(net "GND")
		)
		(pad "14" smd rect
			(at 0.649986 2.474722 270)
			(size 0.3556 1.0668)
			(layers "F.Cu" "F.Mask" "F.Paste")
			(net "GND")
		)
		(pad "15" smd rect
			(at 1.299972 2.474722 270)
			(size 0.3556 1.0668)
			(layers "F.Cu" "F.Mask" "F.Paste")
			(net "TPS74801_P1V2_STBY_SS")
		)
		(pad "16" smd rect
			(at 2.474722 1.299972 270)
			(size 1.0668 0.3556)
			(layers "F.Cu" "F.Mask" "F.Paste")
			(net "TPS74801_P1V2_STBY_FB")
		)
		(pad "17" smd rect
			(at 2.474722 0.649986 270)
			(size 1.0668 0.3556)
			(layers "F.Cu" "F.Mask" "F.Paste")
			(net "GND")
		)
		(pad "18" smd rect
			(at 2.474722 0 270)
			(size 1.0668 0.3556)
			(layers "F.Cu" "F.Mask" "F.Paste")
			(net "TPS74801_P1V2_STBY_OUT")
		)
		(pad "19" smd rect
			(at 2.474722 -0.649986 270)
			(size 1.0668 0.3556)
			(layers "F.Cu" "F.Mask" "F.Paste")
			(net "TPS74801_P1V2_STBY_OUT")
		)
		(pad "20" smd rect
			(at 2.474722 -1.299972 270)
			(size 1.0668 0.3556)
			(layers "F.Cu" "F.Mask" "F.Paste")
			(net "TPS74801_P1V2_STBY_OUT")
		)
		(pad "21" smd rect
			(at 0 0 270)
			(size 3.2512 3.2512)
			(layers "F.Cu" "F.Mask" "F.Paste")
			(net "GND")
		)
	)
	(footprint ""
		(layer "F.Cu")
		(at 199.792336 -134.3025 180)
		(property "Reference" "Q8"
			(at 0 0 180)
			(layer "F.SilkS")
			(hide yes)
			(effects
				(font
					(size 1.27 1.27)
				)
			)
		)
		(property "Value" "2N7002K-1-GP"
			(at 0.127 -8.9662 180)
			(unlocked yes)
			(layer "F.Fab")
			(hide yes)
			(effects
				(font
					(size 1.016 1.016)
					(thickness 0.1524)
				)
			)
		)
		(property "Device Type" "SOT23DGS2D4H44"
			(at 0.127 -10.4902 180)
			(unlocked yes)
			(layer "F.Fab")
			(hide yes)
			(effects
				(font
					(size 1.016 1.016)
					(thickness 0.1524)
				)
			)
		)
		(duplicate_pad_numbers_are_jumpers no)
		(fp_line
			(start 1.651 1.778)
			(end 1.651 -1.778)
			(stroke
				(width 0.1524)
				(type default)
			)
			(layer "F.SilkS")
		)
		(fp_line
			(start 1.651 -1.778)
			(end -1.651 -1.778)
			(stroke
				(width 0.1524)
				(type default)
			)
			(layer "F.SilkS")
		)
		(fp_line
			(start -1.651 1.778)
			(end 1.651 1.778)
			(stroke
				(width 0.1524)
				(type default)
			)
			(layer "F.SilkS")
		)
		(fp_line
			(start -1.651 -1.778)
			(end -1.651 1.778)
			(stroke
				(width 0.1524)
				(type default)
			)
			(layer "F.SilkS")
		)
		(fp_poly
			(pts
				(xy -1.778 1.8796) (xy -1.778 -1.8796) (xy 1.778 -1.8796) (xy 1.778 1.8796)
			)
			(stroke
				(width 0)
				(type default)
			)
			(fill no)
			(layer "F.CrtYd")
		)
		(fp_poly
			(pts
				(xy -1.778 1.8796) (xy -1.778 -1.8796) (xy 1.778 -1.8796) (xy 1.778 1.8796)
			)
			(stroke
				(width 0)
				(type default)
			)
			(fill no)
			(layer "F.Fab")
		)
		(pad "D" smd custom
			(at 0 -0.9525 180)
			(size 0.1905 0.1905)
			(layers "F.Cu" "F.Mask" "F.Paste")
			(net "PWRGD_P1V8")
			(options
				(clearance outline)
				(anchor circle)
			)
			(primitives
				(gr_poly
					(pts
						(arc
							(start -0.1778 0.5715)
							(mid -0.321484 0.511984)
							(end -0.381 0.3683)
						)
						(arc
							(start -0.381 -0.3683)
							(mid -0.321484 -0.511984)
							(end -0.1778 -0.5715)
						)
						(arc
							(start 0.1778 -0.5715)
							(mid 0.321484 -0.511984)
							(end 0.381 -0.3683)
						)
						(arc
							(start 0.381 0.3683)
							(mid 0.321484 0.511984)
							(end 0.1778 0.5715)
						)
					)
					(width 0)
					(fill yes)
				)
			)
		)
		(pad "G" smd custom
			(at -0.98425 0.9525 180)
			(size 0.1905 0.1905)
			(layers "F.Cu" "F.Mask" "F.Paste")
			(net "Q8_G")
			(options
				(clearance outline)
				(anchor circle)
			)
			(primitives
				(gr_poly
					(pts
						(arc
							(start -0.1778 0.5715)
							(mid -0.321484 0.511984)
							(end -0.381 0.3683)
						)
						(arc
							(start -0.381 -0.3683)
							(mid -0.321484 -0.511984)
							(end -0.1778 -0.5715)
						)
						(arc
							(start 0.1778 -0.5715)
							(mid 0.321484 -0.511984)
							(end 0.381 -0.3683)
						)
						(arc
							(start 0.381 0.3683)
							(mid 0.321484 0.511984)
							(end 0.1778 0.5715)
						)
					)
					(width 0)
					(fill yes)
				)
			)
		)
		(pad "S" smd custom
			(at 0.98425 0.9525 180)
			(size 0.1905 0.1905)
			(layers "F.Cu" "F.Mask" "F.Paste")
			(net "GND")
			(options
				(clearance outline)
				(anchor circle)
			)
			(primitives
				(gr_poly
					(pts
						(arc
							(start -0.1778 0.5715)
							(mid -0.321484 0.511984)
							(end -0.381 0.3683)
						)
						(arc
							(start -0.381 -0.3683)
							(mid -0.321484 -0.511984)
							(end -0.1778 -0.5715)
						)
						(arc
							(start 0.1778 -0.5715)
							(mid 0.321484 -0.511984)
							(end 0.381 -0.3683)
						)
						(arc
							(start 0.381 0.3683)
							(mid 0.321484 0.511984)
							(end 0.1778 0.5715)
						)
					)
					(width 0)
					(fill yes)
				)
			)
		)
	)
	(footprint ""
		(layer "F.Cu")
		(at 179.1462 -39.3954)
		(property "Reference" "TP175"
			(at 0 0 0)
			(layer "F.SilkS")
			(hide yes)
			(effects
				(font
					(size 1.27 1.27)
				)
			)
		)
		(property "Value" "TPAD28-2-GP"
			(at -0.0127 -1.6637 0)
			(unlocked yes)
			(layer "F.Fab")
			(hide yes)
			(effects
				(font
					(size 1.016 1.016)
					(thickness 0.1524)
				)
			)
		)
		(property "Device Type" "TPAD28"
			(at -0.0127 -3.1877 0)
			(unlocked yes)
			(layer "F.Fab")
			(hide yes)
			(effects
				(font
					(size 1.016 1.016)
					(thickness 0.1524)
				)
			)
		)
		(duplicate_pad_numbers_are_jumpers no)
		(fp_poly
			(pts
				(arc
					(start 0.3556 0)
					(mid -0.3556 0)
					(end 0.3556 0)
				)
			)
			(stroke
				(width 0)
				(type default)
			)
			(fill no)
			(layer "F.CrtYd")
		)
		(fp_poly
			(pts
				(arc
					(start 0.6096 0)
					(mid -0.6096 0)
					(end 0.6096 0)
				)
			)
			(stroke
				(width 0)
				(type default)
			)
			(fill no)
			(layer "F.Fab")
		)
		(pad "1" smd circle
			(at 0 0)
			(size 0.7112 0.7112)
			(layers "F.Cu" "F.Mask" "F.Paste")
			(net "ZDEF_EXTA_TP_D1")
		)
	)
	(footprint ""
		(layer "F.Cu")
		(at 124.841 -5.588 -90)
		(property "Reference" "R712"
			(at 0 0 270)
			(layer "F.SilkS")
			(hide yes)
			(effects
				(font
					(size 1.27 1.27)
				)
			)
		)
		(property "Value" "0R2J-2-GP"
			(at 0.064008 -3.993896 270)
			(unlocked yes)
			(layer "F.Fab")
			(hide yes)
			(effects
				(font
					(size 1.016 1.016)
					(thickness 0.1524)
				)
			)
		)
		(property "Device Type" "R402H16"
			(at 0.064008 -5.517896 270)
			(unlocked yes)
			(layer "F.Fab")
			(hide yes)
			(effects
				(font
					(size 1.016 1.016)
					(thickness 0.1524)
				)
			)
		)
		(duplicate_pad_numbers_are_jumpers no)
		(fp_line
			(start -0.508 -0.9398)
			(end -0.508 0.9398)
			(stroke
				(width 0.1524)
				(type default)
			)
			(layer "F.SilkS")
		)
		(fp_line
			(start 0.508 -0.9398)
			(end -0.508 -0.9398)
			(stroke
				(width 0.1524)
				(type default)
			)
			(layer "F.SilkS")
		)
		(fp_rect
			(start -0.508 0.9398)
			(end 0.508 -0.9398)
			(stroke
				(width 0)
				(type default)
			)
			(fill no)
			(layer "F.CrtYd")
		)
		(fp_rect
			(start -0.508 0.9398)
			(end 0.508 -0.9398)
			(stroke
				(width 0)
				(type default)
			)
			(fill no)
			(layer "F.Fab")
		)
		(pad "1" smd custom
			(at 0 -0.4445 270)
			(size 0.1397 0.1397)
			(layers "F.Cu" "F.Mask" "F.Paste")
			(net "I2C_IOM_SDA")
			(options
				(clearance outline)
				(anchor circle)
			)
			(primitives
				(gr_poly
					(pts
						(arc
							(start -0.1778 -0.2794)
							(mid -0.249642 -0.249642)
							(end -0.2794 -0.1778)
						)
						(arc
							(start -0.2794 0.1778)
							(mid -0.249642 0.249642)
							(end -0.1778 0.2794)
						)
						(arc
							(start 0.1778 0.2794)
							(mid 0.249642 0.249642)
							(end 0.2794 0.1778)
						)
						(arc
							(start 0.2794 -0.1778)
							(mid 0.249642 -0.249642)
							(end 0.1778 -0.2794)
						)
					)
					(width 0)
					(fill yes)
				)
			)
		)
		(pad "2" smd custom
			(at 0 0.4445 270)
			(size 0.1397 0.1397)
			(layers "F.Cu" "F.Mask" "F.Paste")
			(net "HSW_SDA")
			(options
				(clearance outline)
				(anchor circle)
			)
			(primitives
				(gr_poly
					(pts
						(arc
							(start -0.1778 -0.2794)
							(mid -0.249642 -0.249642)
							(end -0.2794 -0.1778)
						)
						(arc
							(start -0.2794 0.1778)
							(mid -0.249642 0.249642)
							(end -0.1778 0.2794)
						)
						(arc
							(start 0.1778 0.2794)
							(mid 0.249642 0.249642)
							(end 0.2794 0.1778)
						)
						(arc
							(start 0.2794 -0.1778)
							(mid 0.249642 -0.249642)
							(end 0.1778 -0.2794)
						)
					)
					(width 0)
					(fill yes)
				)
			)
		)
	)
	(footprint ""
		(layer "F.Cu")
		(at 41.91 -164.084 180)
		(property "Reference" "R327"
			(at 0 0 180)
			(layer "F.SilkS")
			(hide yes)
			(effects
				(font
					(size 1.27 1.27)
				)
			)
		)
		(property "Value" "4K7R2F-GP"
			(at 0.064008 -3.993896 180)
			(unlocked yes)
			(layer "F.Fab")
			(hide yes)
			(effects
				(font
					(size 1.016 1.016)
					(thickness 0.1524)
				)
			)
		)
		(property "Device Type" "R402H16"
			(at 0.064008 -5.517896 180)
			(unlocked yes)
			(layer "F.Fab")
			(hide yes)
			(effects
				(font
					(size 1.016 1.016)
					(thickness 0.1524)
				)
			)
		)
		(duplicate_pad_numbers_are_jumpers no)
		(fp_line
			(start 0.508 -0.9398)
			(end -0.508 -0.9398)
			(stroke
				(width 0.1524)
				(type default)
			)
			(layer "F.SilkS")
		)
		(fp_line
			(start -0.508 -0.9398)
			(end -0.508 0.9398)
			(stroke
				(width 0.1524)
				(type default)
			)
			(layer "F.SilkS")
		)
		(fp_rect
			(start -0.508 0.9398)
			(end 0.508 -0.9398)
			(stroke
				(width 0)
				(type default)
			)
			(fill no)
			(layer "F.CrtYd")
		)
		(fp_rect
			(start -0.508 0.9398)
			(end 0.508 -0.9398)
			(stroke
				(width 0)
				(type default)
			)
			(fill no)
			(layer "F.Fab")
		)
		(pad "1" smd custom
			(at 0 -0.4445 180)
			(size 0.1397 0.1397)
			(layers "F.Cu" "F.Mask" "F.Paste")
			(net "P3V3_STBY")
			(options
				(clearance outline)
				(anchor circle)
			)
			(primitives
				(gr_poly
					(pts
						(arc
							(start -0.1778 -0.2794)
							(mid -0.249642 -0.249642)
							(end -0.2794 -0.1778)
						)
						(arc
							(start -0.2794 0.1778)
							(mid -0.249642 0.249642)
							(end -0.1778 0.2794)
						)
						(arc
							(start 0.1778 0.2794)
							(mid 0.249642 0.249642)
							(end 0.2794 0.1778)
						)
						(arc
							(start 0.2794 -0.1778)
							(mid 0.249642 -0.249642)
							(end 0.1778 -0.2794)
						)
					)
					(width 0)
					(fill yes)
				)
			)
		)
		(pad "2" smd custom
			(at 0 0.4445 180)
			(size 0.1397 0.1397)
			(layers "F.Cu" "F.Mask" "F.Paste")
			(net "UART_EXP_BMC_RX")
			(options
				(clearance outline)
				(anchor circle)
			)
			(primitives
				(gr_poly
					(pts
						(arc
							(start -0.1778 -0.2794)
							(mid -0.249642 -0.249642)
							(end -0.2794 -0.1778)
						)
						(arc
							(start -0.2794 0.1778)
							(mid -0.249642 0.249642)
							(end -0.1778 0.2794)
						)
						(arc
							(start 0.1778 0.2794)
							(mid 0.249642 0.249642)
							(end 0.2794 0.1778)
						)
						(arc
							(start 0.2794 -0.1778)
							(mid 0.249642 -0.249642)
							(end 0.1778 -0.2794)
						)
					)
					(width 0)
					(fill yes)
				)
			)
		)
	)
	(footprint ""
		(layer "F.Cu")
		(at 191.4144 -86.995 135)
		(property "Reference" "VIA23"
			(at 0 0 135)
			(layer "F.SilkS")
			(hide yes)
			(effects
				(font
					(size 1.27 1.27)
				)
			)
		)
		(property "Value" "85OHM-8L-1D6MM-L16L18-GP"
			(at 4.064105 0.609655 135)
			(unlocked yes)
			(layer "F.Fab")
			(hide yes)
			(effects
				(font
					(size 1.016 1.016)
					(thickness 0.1524)
				)
			)
		)
		(property "Device Type" "VIA-PCIE-4P-368076"
			(at 4.064105 -0.914474 135)
			(unlocked yes)
			(layer "F.Fab")
			(hide yes)
			(effects
				(font
					(size 1.016 1.016)
					(thickness 0.1524)
				)
			)
		)
		(duplicate_pad_numbers_are_jumpers no)
		(fp_poly
			(pts
				(xy -1.841491 -0.381057) (xy 1.841509 -0.381058) (xy 1.841508 0.380942) (xy -1.841491 0.380942)
			)
			(stroke
				(width 0)
				(type default)
			)
			(fill no)
			(layer "F.CrtYd")
		)
		(fp_poly
			(pts
				(xy -1.841491 -0.381057) (xy 1.841509 -0.381058) (xy 1.841508 0.380942) (xy -1.841491 0.380942)
			)
			(stroke
				(width 0)
				(type default)
			)
			(fill no)
			(layer "F.Fab")
		)
		(pad "1" thru_hole circle
			(at -1.460499 0 135)
			(size 0.508 0.508)
			(drill 0.254)
			(layers "*.Cu" "*.Mask")
			(remove_unused_layers no)
			(net "GND")
			(clearance 0.127)
			(thermal_gap 0.127)
		)
		(pad "2" thru_hole circle
			(at -0.4445 0 135)
			(size 0.508 0.508)
			(drill 0.254)
			(layers "*.Cu" "*.Mask")
			(remove_unused_layers no)
			(net "PCIE_COMP_TO_IOM_14_DP")
			(clearance 0.127)
			(thermal_gap 0.127)
		)
		(pad "3" thru_hole circle
			(at 0.4445 0 135)
			(size 0.508 0.508)
			(drill 0.254)
			(layers "*.Cu" "*.Mask")
			(remove_unused_layers no)
			(net "PCIE_COMP_TO_IOM_14_DN")
			(clearance 0.127)
			(thermal_gap 0.127)
		)
		(pad "4" thru_hole circle
			(at 1.460499 0 135)
			(size 0.508 0.508)
			(drill 0.254)
			(layers "*.Cu" "*.Mask")
			(remove_unused_layers no)
			(net "GND")
			(clearance 0.127)
			(thermal_gap 0.127)
		)
	)
)
